(kicad_pcb
	(version 20260206)
	(generator "pcbnew")
	(generator_version "10.0")
	(general
		(thickness 1.6)
		(legacy_teardrops no)
	)
	(paper "A4")
	(title_block
		(title "Wiwynn_Tioga_Pass_MB.brd")
		(comment 1 "Tioga Pass / footprints 3115-3121 of 4770")
	)
	(layers
		(0 "F.Cu" signal "TOP")
		(4 "In1.Cu" signal "L2GND")
		(6 "In2.Cu" signal "L3")
		(8 "In3.Cu" signal "L4GND")
		(10 "In4.Cu" signal "L5")
		(12 "In5.Cu" signal "L6GND")
		(14 "In6.Cu" signal "L7VCC")
		(16 "In7.Cu" signal "L8VCC")
		(18 "In8.Cu" signal "L9GND")
		(20 "In9.Cu" signal "L10")
		(22 "In10.Cu" signal "L11GND")
		(24 "In11.Cu" signal "L12")
		(26 "In12.Cu" signal "L13GND")
		(2 "B.Cu" signal "BOTTOM")
		(9 "F.Adhes" user "F.Adhesive")
		(11 "B.Adhes" user "B.Adhesive")
		(13 "F.Paste" user "Package Geometry/Pastemask Top")
		(15 "B.Paste" user "Package Geometry/Pastemask Bottom")
		(5 "F.SilkS" user "Ref Des/Silkscreen Top")
		(7 "B.SilkS" user "Ref Des/Silkscreen Bottom")
		(1 "F.Mask" user "Board Geometry/Soldermask Top")
		(3 "B.Mask" user "Board Geometry/Soldermask Bottom")
		(17 "Dwgs.User" user "User.Drawings")
		(19 "Cmts.User" user "User.Comments")
		(21 "Eco1.User" user "User.Eco1")
		(23 "Eco2.User" user "User.Eco2")
		(25 "Edge.Cuts" user "Board Geometry/Outline")
		(27 "Margin" user)
		(31 "F.CrtYd" user "Package Geometry/Place Bound Top")
		(29 "B.CrtYd" user "Package Geometry/Place Bound Bottom")
		(35 "F.Fab" user "Ref Des/Assembly Top")
		(33 "B.Fab" user "Ref Des/Assembly Bottom")
	)
	(footprint ""
		(layer "B.Cu")
		(at 361.444794 -42.305986 -90)
		(property "Reference" "R2T30"
			(at 0 0 90)
			(layer "B.SilkS")
			(hide yes)
			(effects
				(font
					(size 1.27 1.27)
				)
				(justify mirror)
			)
		)
		(property "Value" ""
			(at 0 0 90)
			(layer "B.Fab")
			(effects
				(font
					(size 1.27 1.27)
				)
				(justify mirror)
			)
		)
		(duplicate_pad_numbers_are_jumpers no)
		(fp_poly
			(pts
				(xy 0.2794 -0.1016) (xy -0.2794 -0.1016) (xy -0.2794 0.9906) (xy 0.2794 0.9906)
			)
			(stroke
				(width 0)
				(type default)
			)
			(fill no)
			(layer "B.CrtYd")
		)
		(fp_line
			(start -0.2794 0.9906)
			(end -0.2794 -0.1016)
			(stroke
				(width 0.1)
				(type default)
			)
			(layer "B.Fab")
		)
		(fp_line
			(start 0.2794 0.9906)
			(end -0.2794 0.9906)
			(stroke
				(width 0.1)
				(type default)
			)
			(layer "B.Fab")
		)
		(fp_line
			(start -0.2794 -0.1016)
			(end 0.2794 -0.1016)
			(stroke
				(width 0.1)
				(type default)
			)
			(layer "B.Fab")
		)
		(fp_line
			(start 0.2794 -0.1016)
			(end 0.2794 0.9906)
			(stroke
				(width 0.1)
				(type default)
			)
			(layer "B.Fab")
		)
		(pad "1" smd rect
			(at 0 0 90)
			(size 0.508 0.508)
			(layers "B.Cu" "B.Mask" "B.Paste")
			(net "FM_CPU_ERR0_LVT3_K_N")
		)
		(pad "2" smd rect
			(at 0 0.889 90)
			(size 0.508 0.508)
			(layers "B.Cu" "B.Mask" "B.Paste")
			(net "FM_CPU_ERR0_LVT3_N")
		)
		(zone
			(layer "B.Cu")
			(hatch none 0.5)
			(connect_pads
				(clearance 0)
			)
			(min_thickness 0.25)
			(keepout
				(tracks not_allowed)
				(vias allowed)
				(pads allowed)
				(copperpour not_allowed)
				(footprints allowed)
			)
			(placement
				(enabled no)
				(sheetname "")
			)
			(fill
				(thermal_gap 0.5)
				(thermal_bridge_width 0.5)
				(island_removal_mode 0)
			)
			(polygon
				(pts
					(xy 360.809794 -42.051986) (xy 360.809794 -42.559986) (xy 361.190794 -42.559986) (xy 361.190794 -42.051986)
				)
			)
		)
		(zone
			(layer "B.Cu")
			(hatch none 0.5)
			(connect_pads
				(clearance 0)
			)
			(min_thickness 0.25)
			(keepout
				(tracks allowed)
				(vias not_allowed)
				(pads allowed)
				(copperpour not_allowed)
				(footprints allowed)
			)
			(placement
				(enabled no)
				(sheetname "")
			)
			(fill
				(thermal_gap 0.5)
				(thermal_bridge_width 0.5)
				(island_removal_mode 0)
			)
			(polygon
				(pts
					(xy 361.190794 -42.051986) (xy 361.190794 -42.559986) (xy 360.809794 -42.559986) (xy 360.809794 -42.051986)
				)
			)
		)
	)
	(footprint ""
		(layer "B.Cu")
		(at 317.1952 -121.2342 -90)
		(property "Reference" "R3R9"
			(at 0 0 90)
			(layer "B.SilkS")
			(hide yes)
			(effects
				(font
					(size 1.27 1.27)
				)
				(justify mirror)
			)
		)
		(property "Value" ""
			(at 0 0 90)
			(layer "B.Fab")
			(effects
				(font
					(size 1.27 1.27)
				)
				(justify mirror)
			)
		)
		(duplicate_pad_numbers_are_jumpers no)
		(fp_poly
			(pts
				(xy 0.2794 -0.1016) (xy -0.2794 -0.1016) (xy -0.2794 0.9906) (xy 0.2794 0.9906)
			)
			(stroke
				(width 0)
				(type default)
			)
			(fill no)
			(layer "B.CrtYd")
		)
		(fp_line
			(start -0.2794 0.9906)
			(end -0.2794 -0.1016)
			(stroke
				(width 0.1)
				(type default)
			)
			(layer "B.Fab")
		)
		(fp_line
			(start 0.2794 0.9906)
			(end -0.2794 0.9906)
			(stroke
				(width 0.1)
				(type default)
			)
			(layer "B.Fab")
		)
		(fp_line
			(start -0.2794 -0.1016)
			(end 0.2794 -0.1016)
			(stroke
				(width 0.1)
				(type default)
			)
			(layer "B.Fab")
		)
		(fp_line
			(start 0.2794 -0.1016)
			(end 0.2794 0.9906)
			(stroke
				(width 0.1)
				(type default)
			)
			(layer "B.Fab")
		)
		(pad "1" smd rect
			(at 0 0 90)
			(size 0.508 0.508)
			(layers "B.Cu" "B.Mask" "B.Paste")
			(net "SMB_DDR_DEF_VPP_SDA_R")
		)
		(pad "2" smd rect
			(at 0 0.889 90)
			(size 0.508 0.508)
			(layers "B.Cu" "B.Mask" "B.Paste")
			(net "SMB_DDR_DEF_VPP_SDA")
		)
		(zone
			(layer "B.Cu")
			(hatch none 0.5)
			(connect_pads
				(clearance 0)
			)
			(min_thickness 0.25)
			(keepout
				(tracks not_allowed)
				(vias allowed)
				(pads allowed)
				(copperpour not_allowed)
				(footprints allowed)
			)
			(placement
				(enabled no)
				(sheetname "")
			)
			(fill
				(thermal_gap 0.5)
				(thermal_bridge_width 0.5)
				(island_removal_mode 0)
			)
			(polygon
				(pts
					(xy 316.5602 -120.9802) (xy 316.5602 -121.4882) (xy 316.9412 -121.4882) (xy 316.9412 -120.9802)
				)
			)
		)
		(zone
			(layer "B.Cu")
			(hatch none 0.5)
			(connect_pads
				(clearance 0)
			)
			(min_thickness 0.25)
			(keepout
				(tracks allowed)
				(vias not_allowed)
				(pads allowed)
				(copperpour not_allowed)
				(footprints allowed)
			)
			(placement
				(enabled no)
				(sheetname "")
			)
			(fill
				(thermal_gap 0.5)
				(thermal_bridge_width 0.5)
				(island_removal_mode 0)
			)
			(polygon
				(pts
					(xy 316.9412 -120.9802) (xy 316.9412 -121.4882) (xy 316.5602 -121.4882) (xy 316.5602 -120.9802)
				)
			)
		)
	)
	(footprint ""
		(layer "B.Cu")
		(at 462.801208 -137.414254 90)
		(property "Reference" "R1L39"
			(at 0 0 90)
			(layer "B.SilkS")
			(hide yes)
			(effects
				(font
					(size 1.27 1.27)
				)
				(justify mirror)
			)
		)
		(property "Value" ""
			(at 0 0 90)
			(layer "B.Fab")
			(effects
				(font
					(size 1.27 1.27)
				)
				(justify mirror)
			)
		)
		(duplicate_pad_numbers_are_jumpers no)
		(fp_poly
			(pts
				(xy 0.2794 -0.1016) (xy -0.2794 -0.1016) (xy -0.2794 0.9906) (xy 0.2794 0.9906)
			)
			(stroke
				(width 0)
				(type default)
			)
			(fill no)
			(layer "B.CrtYd")
		)
		(fp_line
			(start 0.2794 -0.1016)
			(end 0.2794 0.9906)
			(stroke
				(width 0.1)
				(type default)
			)
			(layer "B.Fab")
		)
		(fp_line
			(start -0.2794 -0.1016)
			(end 0.2794 -0.1016)
			(stroke
				(width 0.1)
				(type default)
			)
			(layer "B.Fab")
		)
		(fp_line
			(start 0.2794 0.9906)
			(end -0.2794 0.9906)
			(stroke
				(width 0.1)
				(type default)
			)
			(layer "B.Fab")
		)
		(fp_line
			(start -0.2794 0.9906)
			(end -0.2794 -0.1016)
			(stroke
				(width 0.1)
				(type default)
			)
			(layer "B.Fab")
		)
		(pad "1" smd rect
			(at 0 0 270)
			(size 0.508 0.508)
			(layers "B.Cu" "B.Mask" "B.Paste")
			(net "P1V05_PCH_STBY")
		)
		(pad "2" smd rect
			(at 0 0.889 270)
			(size 0.508 0.508)
			(layers "B.Cu" "B.Mask" "B.Paste")
			(net "XDP_PRDY_N")
		)
		(zone
			(layer "B.Cu")
			(hatch none 0.5)
			(connect_pads
				(clearance 0)
			)
			(min_thickness 0.25)
			(keepout
				(tracks allowed)
				(vias not_allowed)
				(pads allowed)
				(copperpour not_allowed)
				(footprints allowed)
			)
			(placement
				(enabled no)
				(sheetname "")
			)
			(fill
				(thermal_gap 0.5)
				(thermal_bridge_width 0.5)
				(island_removal_mode 0)
			)
			(polygon
				(pts
					(xy 463.055208 -137.668254) (xy 463.055208 -137.160254) (xy 463.436208 -137.160254) (xy 463.436208 -137.668254)
				)
			)
		)
		(zone
			(layer "B.Cu")
			(hatch none 0.5)
			(connect_pads
				(clearance 0)
			)
			(min_thickness 0.25)
			(keepout
				(tracks not_allowed)
				(vias allowed)
				(pads allowed)
				(copperpour not_allowed)
				(footprints allowed)
			)
			(placement
				(enabled no)
				(sheetname "")
			)
			(fill
				(thermal_gap 0.5)
				(thermal_bridge_width 0.5)
				(island_removal_mode 0)
			)
			(polygon
				(pts
					(xy 463.436208 -137.668254) (xy 463.436208 -137.160254) (xy 463.055208 -137.160254) (xy 463.055208 -137.668254)
				)
			)
		)
	)
	(footprint ""
		(layer "B.Cu")
		(at 164.973 -60.6552 90)
		(property "Reference" "C6R5"
			(at -0.02667 10.541 0)
			(unlocked yes)
			(layer "B.SilkS")
			(effects
				(font
					(size 0.7874 0.5842)
					(thickness 0.1524)
				)
				(justify mirror)
			)
		)
		(property "Value" ""
			(at 0 0 90)
			(layer "B.Fab")
			(effects
				(font
					(size 1.27 1.27)
				)
				(justify mirror)
			)
		)
		(duplicate_pad_numbers_are_jumpers no)
		(fp_line
			(start 2.563114 -1.616456)
			(end 2.563114 1.633728)
			(stroke
				(width 0.1524)
				(type default)
			)
			(layer "B.SilkS")
		)
		(fp_line
			(start 1.6002 -1.616456)
			(end 2.563114 -1.616456)
			(stroke
				(width 0.1524)
				(type default)
			)
			(layer "B.SilkS")
		)
		(fp_line
			(start -1.6002 -1.616456)
			(end -2.504948 -1.616456)
			(stroke
				(width 0.1524)
				(type default)
			)
			(layer "B.SilkS")
		)
		(fp_line
			(start -2.504948 -1.616456)
			(end -2.504948 1.633728)
			(stroke
				(width 0.1524)
				(type default)
			)
			(layer "B.SilkS")
		)
		(fp_line
			(start 2.563114 1.633728)
			(end 1.6002 1.633728)
			(stroke
				(width 0.1524)
				(type default)
			)
			(layer "B.SilkS")
		)
		(fp_line
			(start -2.504948 1.633728)
			(end -1.6002 1.633728)
			(stroke
				(width 0.1524)
				(type default)
			)
			(layer "B.SilkS")
		)
		(fp_line
			(start 2.286 7.366)
			(end 2.286 1.632712)
			(stroke
				(width 0.1524)
				(type default)
			)
			(layer "B.SilkS")
		)
		(fp_line
			(start 2.286 7.366)
			(end 1.60147 7.366)
			(stroke
				(width 0.1524)
				(type default)
			)
			(layer "B.SilkS")
		)
		(fp_line
			(start -2.286 7.366)
			(end -2.286 1.63195)
			(stroke
				(width 0.1524)
				(type default)
			)
			(layer "B.SilkS")
		)
		(fp_line
			(start -2.286 7.366)
			(end -1.600708 7.366)
			(stroke
				(width 0.1524)
				(type default)
			)
			(layer "B.SilkS")
		)
		(fp_rect
			(start 2.286 7.366)
			(end -2.286 -0.254)
			(stroke
				(width 0)
				(type default)
			)
			(fill no)
			(layer "B.CrtYd")
		)
		(fp_line
			(start 2.286 -0.254)
			(end -2.286 -0.254)
			(stroke
				(width 0.1)
				(type default)
			)
			(layer "B.Fab")
		)
		(fp_line
			(start -2.286 -0.254)
			(end -2.286 7.366)
			(stroke
				(width 0.1)
				(type default)
			)
			(layer "B.Fab")
		)
		(fp_line
			(start 2.286 7.366)
			(end 2.286 -0.254)
			(stroke
				(width 0.1)
				(type default)
			)
			(layer "B.Fab")
		)
		(fp_line
			(start -2.286 7.366)
			(end 2.286 7.366)
			(stroke
				(width 0.1)
				(type default)
			)
			(layer "B.Fab")
		)
		(pad "1" smd rect
			(at 0 0 270)
			(size 2.54 3.048)
			(layers "B.Cu" "B.Mask" "B.Paste")
			(net "PVCCIO_CPU1")
		)
		(pad "2" smd rect
			(at 0 7.112 270)
			(size 2.54 3.048)
			(layers "B.Cu" "B.Mask" "B.Paste")
			(net "GND")
		)
	)
	(footprint ""
		(layer "B.Cu")
		(at -3.47726 -117.89156)
		(property "Reference" "R9M19"
			(at 0 0 0)
			(layer "B.SilkS")
			(hide yes)
			(effects
				(font
					(size 1.27 1.27)
				)
				(justify mirror)
			)
		)
		(property "Value" ""
			(at 0 0 0)
			(layer "B.Fab")
			(effects
				(font
					(size 1.27 1.27)
				)
				(justify mirror)
			)
		)
		(duplicate_pad_numbers_are_jumpers no)
		(fp_rect
			(start -0.2794 0.9906)
			(end 0.2794 -0.1016)
			(stroke
				(width 0)
				(type default)
			)
			(fill no)
			(layer "B.CrtYd")
		)
		(fp_line
			(start -0.2794 -0.1016)
			(end 0.2794 -0.1016)
			(stroke
				(width 0.1)
				(type default)
			)
			(layer "B.Fab")
		)
		(fp_line
			(start -0.2794 0.9906)
			(end -0.2794 -0.1016)
			(stroke
				(width 0.1)
				(type default)
			)
			(layer "B.Fab")
		)
		(fp_line
			(start 0.2794 -0.1016)
			(end 0.2794 0.9906)
			(stroke
				(width 0.1)
				(type default)
			)
			(layer "B.Fab")
		)
		(fp_line
			(start 0.2794 0.9906)
			(end -0.2794 0.9906)
			(stroke
				(width 0.1)
				(type default)
			)
			(layer "B.Fab")
		)
		(pad "1" smd rect
			(at 0 0 180)
			(size 0.508 0.508)
			(layers "B.Cu" "B.Mask" "B.Paste")
			(net "PVCCIO_CPU1")
		)
		(pad "2" smd rect
			(at 0 0.889 180)
			(size 0.508 0.508)
			(layers "B.Cu" "B.Mask" "B.Paste")
			(net "SMB_CPU1_PE_HP_GTL_R_SCL")
		)
		(zone
			(layer "B.Cu")
			(hatch none 0.5)
			(connect_pads
				(clearance 0)
			)
			(min_thickness 0.25)
			(keepout
				(tracks allowed)
				(vias not_allowed)
				(pads allowed)
				(copperpour not_allowed)
				(footprints allowed)
			)
			(placement
				(enabled no)
				(sheetname "")
			)
			(fill
				(thermal_gap 0.5)
				(thermal_bridge_width 0.5)
				(island_removal_mode 0)
			)
			(polygon
				(pts
					(xy -3.73126 -117.25656) (xy -3.22326 -117.25656) (xy -3.22326 -117.63756) (xy -3.73126 -117.63756)
				)
			)
		)
		(zone
			(layer "B.Cu")
			(hatch none 0.5)
			(connect_pads
				(clearance 0)
			)
			(min_thickness 0.25)
			(keepout
				(tracks not_allowed)
				(vias allowed)
				(pads allowed)
				(copperpour not_allowed)
				(footprints allowed)
			)
			(placement
				(enabled no)
				(sheetname "")
			)
			(fill
				(thermal_gap 0.5)
				(thermal_bridge_width 0.5)
				(island_removal_mode 0)
			)
			(polygon
				(pts
					(xy -3.73126 -117.25656) (xy -3.22326 -117.25656) (xy -3.22326 -117.63756) (xy -3.73126 -117.63756)
				)
			)
		)
	)
	(footprint ""
		(layer "B.Cu")
		(at 111.000032 -149.8092 90)
		(property "Reference" "C5G105"
			(at -1.14681 0.76708 180)
			(unlocked yes)
			(layer "B.SilkS")
			(effects
				(font
					(size 0.7874 0.5842)
					(thickness 0.1524)
				)
				(justify mirror)
			)
		)
		(property "Value" ""
			(at 0 0 90)
			(layer "B.Fab")
			(effects
				(font
					(size 1.27 1.27)
				)
				(justify mirror)
			)
		)
		(duplicate_pad_numbers_are_jumpers no)
		(fp_rect
			(start -0.4953 -0.2032)
			(end 0.4953 1.6002)
			(stroke
				(width 0)
				(type default)
			)
			(fill no)
			(layer "B.CrtYd")
		)
		(fp_line
			(start 0.4953 -0.2032)
			(end -0.4953 -0.2032)
			(stroke
				(width 0.1)
				(type default)
			)
			(layer "B.Fab")
		)
		(fp_line
			(start -0.4953 -0.2032)
			(end -0.4953 1.6002)
			(stroke
				(width 0.1)
				(type default)
			)
			(layer "B.Fab")
		)
		(fp_line
			(start 0.4953 1.6002)
			(end 0.4953 -0.2032)
			(stroke
				(width 0.1)
				(type default)
			)
			(layer "B.Fab")
		)
		(fp_line
			(start -0.4953 1.6002)
			(end 0.4953 1.6002)
			(stroke
				(width 0.1)
				(type default)
			)
			(layer "B.Fab")
		)
		(pad "1" smd rect
			(at 0 0 270)
			(size 0.762 0.889)
			(layers "B.Cu" "B.Mask" "B.Paste")
			(net "PVDDQ_KLM")
		)
		(pad "2" smd rect
			(at 0 1.397 270)
			(size 0.762 0.889)
			(layers "B.Cu" "B.Mask" "B.Paste")
			(net "GND")
		)
		(zone
			(layer "B.Cu")
			(hatch none 0.5)
			(connect_pads
				(clearance 0)
			)
			(min_thickness 0.25)
			(keepout
				(tracks not_allowed)
				(vias allowed)
				(pads allowed)
				(copperpour not_allowed)
				(footprints allowed)
			)
			(placement
				(enabled no)
				(sheetname "")
			)
			(fill
				(thermal_gap 0.5)
				(thermal_bridge_width 0.5)
				(island_removal_mode 0)
			)
			(polygon
				(pts
					(xy 111.444532 -149.4282) (xy 111.952532 -149.4282) (xy 111.952532 -150.1902) (xy 111.444532 -150.1902)
				)
			)
		)
	)
	(footprint ""
		(layer "B.Cu")
		(at 483.616 -113.06302)
		(property "Reference" "C1M25"
			(at 0 0 0)
			(layer "B.SilkS")
			(hide yes)
			(effects
				(font
					(size 1.27 1.27)
				)
				(justify mirror)
			)
		)
		(property "Value" ""
			(at 0 0 0)
			(layer "B.Fab")
			(effects
				(font
					(size 1.27 1.27)
				)
				(justify mirror)
			)
		)
		(duplicate_pad_numbers_are_jumpers no)
		(fp_rect
			(start -0.3048 0.9906)
			(end 0.3048 -0.1016)
			(stroke
				(width 0)
				(type default)
			)
			(fill no)
			(layer "B.CrtYd")
		)
		(fp_line
			(start -0.3048 -0.1016)
			(end 0.3048 -0.1016)
			(stroke
				(width 0.1)
				(type default)
			)
			(layer "B.Fab")
		)
		(fp_line
			(start -0.3048 0.9906)
			(end -0.3048 -0.1016)
			(stroke
				(width 0.1)
				(type default)
			)
			(layer "B.Fab")
		)
		(fp_line
			(start 0.3048 -0.1016)
			(end 0.3048 0.9906)
			(stroke
				(width 0.1)
				(type default)
			)
			(layer "B.Fab")
		)
		(fp_line
			(start 0.3048 0.9906)
			(end -0.3048 0.9906)
			(stroke
				(width 0.1)
				(type default)
			)
			(layer "B.Fab")
		)
		(pad "1" smd rect
			(at 0 0 180)
			(size 0.508 0.508)
			(layers "B.Cu" "B.Mask" "B.Paste")
			(net "P3V3_STBY")
		)
		(pad "2" smd rect
			(at 0 0.889 180)
			(size 0.508 0.508)
			(layers "B.Cu" "B.Mask" "B.Paste")
			(net "GND")
		)
		(zone
			(layer "B.Cu")
			(hatch none 0.5)
			(connect_pads
				(clearance 0)
			)
			(min_thickness 0.25)
			(keepout
				(tracks not_allowed)
				(vias allowed)
				(pads allowed)
				(copperpour not_allowed)
				(footprints allowed)
			)
			(placement
				(enabled no)
				(sheetname "")
			)
			(fill
				(thermal_gap 0.5)
				(thermal_bridge_width 0.5)
				(island_removal_mode 0)
			)
			(polygon
				(pts
					(xy 483.362 -112.42802) (xy 483.87 -112.42802) (xy 483.87 -112.80902) (xy 483.362 -112.80902)
				)
			)
		)
		(zone
			(layer "B.Cu")
			(hatch none 0.5)
			(connect_pads
				(clearance 0)
			)
			(min_thickness 0.25)
			(keepout
				(tracks allowed)
				(vias not_allowed)
				(pads allowed)
				(copperpour not_allowed)
				(footprints allowed)
			)
			(placement
				(enabled no)
				(sheetname "")
			)
			(fill
				(thermal_gap 0.5)
				(thermal_bridge_width 0.5)
				(island_removal_mode 0)
			)
			(polygon
				(pts
					(xy 483.362 -112.42802) (xy 483.87 -112.42802) (xy 483.87 -112.80902) (xy 483.362 -112.80902)
				)
			)
		)
	)
)
